(kicad_pcb
	(version 20221018)
	(generator pcbnew)
	(general
    (thickness 1.562)
  )
	(paper "A4")
	(title_block
    (title "Thunderbolt PCIe Adaper")
    (date "2024-07-09")
    (rev "1.0.3")
    (comment 1 "www.antmicro.com")
    (comment 2 "Antmicro Ltd.")
		(comment 9 "footprints 115-123 of 271")
	)
	(layers
    (0 "F.Cu" signal)
    (1 "In1.Cu" signal)
    (2 "In2.Cu" signal)
    (3 "In3.Cu" signal)
    (4 "In4.Cu" signal)
    (31 "B.Cu" signal)
    (32 "B.Adhes" user "B.Adhesive")
    (33 "F.Adhes" user "F.Adhesive")
    (34 "B.Paste" user)
    (35 "F.Paste" user)
    (36 "B.SilkS" user "B.Silkscreen")
    (37 "F.SilkS" user "F.Silkscreen")
    (38 "B.Mask" user)
    (39 "F.Mask" user)
    (40 "Dwgs.User" user "User.Drawings")
    (41 "Cmts.User" user "User.Comments")
    (42 "Eco1.User" user "User.Eco1")
    (43 "Eco2.User" user "User.Eco2")
    (44 "Edge.Cuts" user)
    (45 "Margin" user)
    (46 "B.CrtYd" user "B.Courtyard")
    (47 "F.CrtYd" user "F.Courtyard")
    (48 "B.Fab" user)
    (49 "F.Fab" user)
  )
	(footprint "antmicro-footprints:C_0402_1005Metric" (layer "B.Cu")
    (at 111.725 80.65)
    (descr "Capacitor SMD 0402")
    (tags "capacitor SMD 0402")
    (property "Author" "Antmicro")
    (property "Dielectric" "X5R")
    (property "License" "Apache-2.0")
    (property "MPN" "GRM155R61H104KE14D")
    (property "Manufacturer" "Murata")
    (property "Sheetfile" "power.kicad_sch")
    (property "Sheetname" "Power")
    (property "Val" "100n")
    (property "Voltage" "50V")
    (property "ki_description" "SMD Multilayer Ceramic Capacitor, 0.1 µF, 50 V, 0402 [1005 Metric], ± 10%, X5R, GRM Series")
    (property "ki_keywords" "0402, SMT, CAPACITOR, PASSIVE, CERAMIC, MLCC")
    (attr smd)
    (fp_text reference "C32" (at 1.051 -4.704 180) (layer "B.SilkS")
        (effects (font (size 0.7 0.7) (thickness 0.15)) (justify left bottom mirror))
    )
    (fp_text value "C_100n_0402" (at -1.022927 -2.155213 180) (layer "B.Fab")
        (effects (font (size 0.7 0.7) (thickness 0.15)) (justify left bottom mirror))
    )
    (fp_text user "Author: Antmicro" (at -0.939 -3.399 180) (layer "B.Fab") hide
        (effects (font (size 0.7 0.7) (thickness 0.15)) (justify left bottom mirror))
    )
    (fp_text user "${REFERENCE}" (at -0.939 -4.599 180) (layer "B.Fab") hide
        (effects (font (size 0.7 0.7) (thickness 0.15)) (justify left bottom mirror))
    )
    (fp_text user "License: Apache-2.0" (at -0.939 -5.799 180) (layer "B.Fab") hide
        (effects (font (size 0.7 0.7) (thickness 0.15)) (justify left bottom mirror))
    )
    (fp_rect (start -0.925 0.47) (end 0.925 -0.47)
      (stroke (width 0.05) (type default)) (fill none) (layer "B.CrtYd"))
    (fp_line (start -0.494 -0.248) (end -0.494 0.25)
      (stroke (width 0.15) (type solid)) (layer "B.Fab"))
    (fp_line (start -0.494 0.25) (end 0.504 0.25)
      (stroke (width 0.15) (type solid)) (layer "B.Fab"))
    (fp_line (start 0.504 -0.248) (end -0.494 -0.248)
      (stroke (width 0.15) (type solid)) (layer "B.Fab"))
    (fp_line (start 0.504 0.25) (end 0.504 -0.248)
      (stroke (width 0.15) (type solid)) (layer "B.Fab"))
    (pad "1" smd roundrect (at -0.48 0) (size 0.59 0.64) (layers "B.Cu" "B.Paste" "B.Mask") (roundrect_rratio 0.25)
      (net 1 "GND") (pintype "passive"))
    (pad "2" smd roundrect (at 0.48 0) (size 0.59 0.64) (layers "B.Cu" "B.Paste" "B.Mask") (roundrect_rratio 0.25)
      (net 75 "Net-(C32-Pad2)") (pintype "passive"))
  )
	(footprint "antmicro-footprints:R_0402_1005Metric" (layer "B.Cu")
    (at 136.2 66.82 -90)
    (descr "Resistor SMD 0402")
    (tags "resistor SMD 0402")
    (property "Author" "Antmicro")
    (property "License" "Apache-2.0")
    (property "MPN" "CR0402-FX-1002GLF")
    (property "Manufacturer" "Bourns")
    (property "Sheetfile" "tb.kicad_sch")
    (property "Sheetname" "TB Controller")
    (property "Tolerance" "1%")
    (property "Val" "10k")
    (property "ki_description" "SMD Chip Resistor, 10 kohm, ± 1%, 62.5 mW, 0402 [1005 Metric], Thick Film, General Purpose")
    (property "ki_keywords" "0402, SMT, RESISTOR, PASSIVE")
    (attr smd)
    (fp_text reference "R66" (at -3.066 -0.325 90) (layer "B.SilkS")
        (effects (font (size 0.7 0.7) (thickness 0.15)) (justify left bottom mirror))
    )
    (fp_text value "R_10k_0402" (at -1.011843 -1.772047 90) (layer "B.Fab")
        (effects (font (size 0.7 0.7) (thickness 0.15)) (justify left bottom mirror))
    )
    (fp_text user "Author: Antmicro" (at -0.95 -4.169 90) (layer "B.Fab") hide
        (effects (font (size 0.7 0.7) (thickness 0.15)) (justify left bottom mirror))
    )
    (fp_text user "License: Apache-2.0" (at -0.95 -5.169 90) (layer "B.Fab") hide
        (effects (font (size 0.7 0.7) (thickness 0.15)) (justify left bottom mirror))
    )
    (fp_text user "${REFERENCE}" (at -0.95 -3.168 90) (layer "B.Fab") hide
        (effects (font (size 0.7 0.7) (thickness 0.15)) (justify left bottom mirror))
    )
    (fp_rect (start -0.925 0.47) (end 0.925 -0.47)
      (stroke (width 0.05) (type default)) (fill none) (layer "B.CrtYd"))
    (fp_rect (start -0.5 0.25) (end 0.5 -0.25)
      (stroke (width 0.15) (type solid)) (fill none) (layer "B.Fab"))
    (pad "1" smd roundrect (at -0.48 0 270) (size 0.59 0.64) (layers "B.Cu" "B.Paste" "B.Mask") (roundrect_rratio 0.25)
      (net 2 "3V3_SYS") (pintype "passive"))
    (pad "2" smd roundrect (at 0.48 0 270) (size 0.59 0.64) (layers "B.Cu" "B.Paste" "B.Mask") (roundrect_rratio 0.25)
      (net 180 "Net-(U4D-TCK)") (pintype "passive"))
  )
	(footprint "antmicro-footprints:R_0402_1005Metric" (layer "B.Cu")
    (at 131.075 70.72 90)
    (descr "Resistor SMD 0402")
    (tags "resistor SMD 0402")
    (property "Author" "Antmicro")
    (property "License" "Apache-2.0")
    (property "MPN" "CR0402-FX-1003GLF")
    (property "Manufacturer" "Bourns")
    (property "Sheetfile" "tb.kicad_sch")
    (property "Sheetname" "TB Controller")
    (property "Tolerance" "1%")
    (property "Val" "100k")
    (property "ki_description" "SMD Chip Resistor, 100 kohm, ± 1%, 62.5 mW, 0402 [1005 Metric], Thick Film, General Purpose")
    (property "ki_keywords" "0402, SMT, RESISTOR, PASSIVE")
    (attr smd)
    (fp_text reference "R81" (at -0.908 0.361 270) (layer "B.SilkS")
        (effects (font (size 0.7 0.7) (thickness 0.15)) (justify left bottom mirror))
    )
    (fp_text value "R_100k_0402" (at -1.011843 -1.772047 270) (layer "B.Fab")
        (effects (font (size 0.7 0.7) (thickness 0.15)) (justify left bottom mirror))
    )
    (fp_text user "Author: Antmicro" (at -0.95 -4.169 270) (layer "B.Fab") hide
        (effects (font (size 0.7 0.7) (thickness 0.15)) (justify left bottom mirror))
    )
    (fp_text user "License: Apache-2.0" (at -0.95 -5.169 270) (layer "B.Fab") hide
        (effects (font (size 0.7 0.7) (thickness 0.15)) (justify left bottom mirror))
    )
    (fp_text user "${REFERENCE}" (at -0.95 -3.168 270) (layer "B.Fab") hide
        (effects (font (size 0.7 0.7) (thickness 0.15)) (justify left bottom mirror))
    )
    (fp_rect (start -0.925 0.47) (end 0.925 -0.47)
      (stroke (width 0.05) (type default)) (fill none) (layer "B.CrtYd"))
    (fp_rect (start -0.5 0.25) (end 0.5 -0.25)
      (stroke (width 0.15) (type solid)) (fill none) (layer "B.Fab"))
    (pad "1" smd roundrect (at -0.48 0 90) (size 0.59 0.64) (layers "B.Cu" "B.Paste" "B.Mask") (roundrect_rratio 0.25)
      (net 196 "Net-(U4C-GPIO_7)") (pintype "passive"))
    (pad "2" smd roundrect (at 0.48 0 90) (size 0.59 0.64) (layers "B.Cu" "B.Paste" "B.Mask") (roundrect_rratio 0.25)
      (net 1 "GND") (pintype "passive"))
  )
	(footprint "antmicro-footprints:R_0402_1005Metric" (layer "B.Cu")
    (at 132.1 66.82 -90)
    (descr "Resistor SMD 0402")
    (tags "resistor SMD 0402")
    (property "Author" "Antmicro")
    (property "License" "Apache-2.0")
    (property "MPN" "CR0402-FX-1002GLF")
    (property "Manufacturer" "Bourns")
    (property "Sheetfile" "tb.kicad_sch")
    (property "Sheetname" "TB Controller")
    (property "Tolerance" "1%")
    (property "Val" "10k")
    (property "ki_description" "SMD Chip Resistor, 10 kohm, ± 1%, 62.5 mW, 0402 [1005 Metric], Thick Film, General Purpose")
    (property "ki_keywords" "0402, SMT, RESISTOR, PASSIVE")
    (attr smd)
    (fp_text reference "R64" (at -3.066 -0.325 90) (layer "B.SilkS")
        (effects (font (size 0.7 0.7) (thickness 0.15)) (justify left bottom mirror))
    )
    (fp_text value "R_10k_0402" (at -1.011843 -1.772047 90) (layer "B.Fab")
        (effects (font (size 0.7 0.7) (thickness 0.15)) (justify left bottom mirror))
    )
    (fp_text user "License: Apache-2.0" (at -0.95 -5.169 90) (layer "B.Fab") hide
        (effects (font (size 0.7 0.7) (thickness 0.15)) (justify left bottom mirror))
    )
    (fp_text user "Author: Antmicro" (at -0.95 -4.169 90) (layer "B.Fab") hide
        (effects (font (size 0.7 0.7) (thickness 0.15)) (justify left bottom mirror))
    )
    (fp_text user "${REFERENCE}" (at -0.95 -3.168 90) (layer "B.Fab") hide
        (effects (font (size 0.7 0.7) (thickness 0.15)) (justify left bottom mirror))
    )
    (fp_rect (start -0.925 0.47) (end 0.925 -0.47)
      (stroke (width 0.05) (type default)) (fill none) (layer "B.CrtYd"))
    (fp_rect (start -0.5 0.25) (end 0.5 -0.25)
      (stroke (width 0.15) (type solid)) (fill none) (layer "B.Fab"))
    (pad "1" smd roundrect (at -0.48 0 270) (size 0.59 0.64) (layers "B.Cu" "B.Paste" "B.Mask") (roundrect_rratio 0.25)
      (net 2 "3V3_SYS") (pintype "passive"))
    (pad "2" smd roundrect (at 0.48 0 270) (size 0.59 0.64) (layers "B.Cu" "B.Paste" "B.Mask") (roundrect_rratio 0.25)
      (net 178 "Net-(U4D-TDI)") (pintype "passive"))
  )
	(footprint "antmicro-footprints:R_0402_1005Metric" (layer "B.Cu")
    (at 136.75 76.925)
    (descr "Resistor SMD 0402")
    (tags "resistor SMD 0402")
    (property "Author" "Antmicro")
    (property "License" "Apache-2.0")
    (property "MPN" "ERJ-H2RD4751X")
    (property "Manufacturer" "Panasonic")
    (property "Sheetfile" "tb.kicad_sch")
    (property "Sheetname" "TB Controller")
    (property "Tolerance" "0.5%")
    (property "Val" "4k75")
    (property "ki_description" "SMD Chip Resistor, 4.75 kohm, ± 0.5%, 100 mW, 0402 [1005 Metric], Thick Film, High Temperature")
    (property "ki_keywords" "0402, SMT, RESISTOR, PASSIVE")
    (attr smd)
    (fp_text reference "R69" (at 17.682 7.657 180) (layer "B.SilkS")
        (effects (font (size 0.7 0.7) (thickness 0.15)) (justify left bottom mirror))
    )
    (fp_text value "R_4k75_0.5%_0402" (at -1.011843 -1.772047 180) (layer "B.Fab")
        (effects (font (size 0.7 0.7) (thickness 0.15)) (justify left bottom mirror))
    )
    (fp_text user "License: Apache-2.0" (at -0.95 -5.169 180) (layer "B.Fab") hide
        (effects (font (size 0.7 0.7) (thickness 0.15)) (justify left bottom mirror))
    )
    (fp_text user "${REFERENCE}" (at -0.95 -3.168 180) (layer "B.Fab") hide
        (effects (font (size 0.7 0.7) (thickness 0.15)) (justify left bottom mirror))
    )
    (fp_text user "Author: Antmicro" (at -0.95 -4.169 180) (layer "B.Fab") hide
        (effects (font (size 0.7 0.7) (thickness 0.15)) (justify left bottom mirror))
    )
    (fp_rect (start -0.925 0.47) (end 0.925 -0.47)
      (stroke (width 0.05) (type default)) (fill none) (layer "B.CrtYd"))
    (fp_rect (start -0.5 0.25) (end 0.5 -0.25)
      (stroke (width 0.15) (type solid)) (fill none) (layer "B.Fab"))
    (pad "1" smd roundrect (at -0.48 0) (size 0.59 0.64) (layers "B.Cu" "B.Paste" "B.Mask") (roundrect_rratio 0.25)
      (net 183 "Net-(U4D-RSENSE)") (pintype "passive"))
    (pad "2" smd roundrect (at 0.48 0) (size 0.59 0.64) (layers "B.Cu" "B.Paste" "B.Mask") (roundrect_rratio 0.25)
      (net 184 "Net-(U4D-RBIAS)") (pintype "passive"))
  )
	(footprint "antmicro-footprints:R_0402_1005Metric" (layer "B.Cu")
    (at 130.7 82.13 180)
    (descr "Resistor SMD 0402")
    (tags "resistor SMD 0402")
    (property "Author" "Antmicro")
    (property "License" "Apache-2.0")
    (property "MPN" "CR0402-FX-3011GLF")
    (property "Manufacturer" "Bourns")
    (property "Sheetfile" "tb.kicad_sch")
    (property "Sheetname" "TB Controller")
    (property "Tolerance" "1%")
    (property "Val" "3k01")
    (property "ki_description" "SMD Chip Resistor, 3.01 kohm, ± 1%, 62.5 mW, 0402 [1005 Metric], Thick Film, General Purpose")
    (property "ki_keywords" "0402, SMT, RESISTOR, PASSIVE")
    (attr smd)
    (fp_text reference "R74" (at -17.509 -7.405) (layer "B.SilkS")
        (effects (font (size 0.7 0.7) (thickness 0.15)) (justify left bottom mirror))
    )
    (fp_text value "R_3k01_0402" (at -1.011843 -1.772047) (layer "B.Fab")
        (effects (font (size 0.7 0.7) (thickness 0.15)) (justify left bottom mirror))
    )
    (fp_text user "Author: Antmicro" (at -0.95 -4.169) (layer "B.Fab") hide
        (effects (font (size 0.7 0.7) (thickness 0.15)) (justify left bottom mirror))
    )
    (fp_text user "${REFERENCE}" (at -0.95 -3.168) (layer "B.Fab") hide
        (effects (font (size 0.7 0.7) (thickness 0.15)) (justify left bottom mirror))
    )
    (fp_text user "License: Apache-2.0" (at -0.95 -5.169) (layer "B.Fab") hide
        (effects (font (size 0.7 0.7) (thickness 0.15)) (justify left bottom mirror))
    )
    (fp_rect (start -0.925 0.47) (end 0.925 -0.47)
      (stroke (width 0.05) (type default)) (fill none) (layer "B.CrtYd"))
    (fp_rect (start -0.5 0.25) (end 0.5 -0.25)
      (stroke (width 0.15) (type solid)) (fill none) (layer "B.Fab"))
    (pad "1" smd roundrect (at -0.48 0 180) (size 0.59 0.64) (layers "B.Cu" "B.Paste" "B.Mask") (roundrect_rratio 0.25)
      (net 189 "Net-(U4B-PCIE_RBIAS)") (pintype "passive"))
    (pad "2" smd roundrect (at 0.48 0 180) (size 0.59 0.64) (layers "B.Cu" "B.Paste" "B.Mask") (roundrect_rratio 0.25)
      (net 1 "GND") (pintype "passive"))
  )
	(footprint "antmicro-footprints:R_0402_1005Metric" (layer "B.Cu")
    (at 107.425 81.15 90)
    (descr "Resistor SMD 0402")
    (tags "resistor SMD 0402")
    (property "Author" "Antmicro")
    (property "License" "Apache-2.0")
    (property "MPN" "CR0402-FX-2402GLF")
    (property "Manufacturer" "Bourns")
    (property "Sheetfile" "power.kicad_sch")
    (property "Sheetname" "Power")
    (property "Tolerance" "1%")
    (property "Val" "24k")
    (property "ki_description" "SMD Chip Resistor, 24 kohm, ± 1%, 100 mW, 0402 [1005 Metric], Thick Film, Precision")
    (property "ki_keywords" "0402, SMT, RESISTOR, PASSIVE")
    (attr smd)
    (fp_text reference "R7" (at 0.632 -0.745 270) (layer "B.SilkS")
        (effects (font (size 0.7 0.7) (thickness 0.15)) (justify left bottom mirror))
    )
    (fp_text value "R_24k_0402" (at -1.011843 -1.772047 270) (layer "B.Fab")
        (effects (font (size 0.7 0.7) (thickness 0.15)) (justify left bottom mirror))
    )
    (fp_text user "Author: Antmicro" (at -0.95 -4.169 270) (layer "B.Fab") hide
        (effects (font (size 0.7 0.7) (thickness 0.15)) (justify left bottom mirror))
    )
    (fp_text user "${REFERENCE}" (at -0.95 -3.168 270) (layer "B.Fab") hide
        (effects (font (size 0.7 0.7) (thickness 0.15)) (justify left bottom mirror))
    )
    (fp_text user "License: Apache-2.0" (at -0.95 -5.169 270) (layer "B.Fab") hide
        (effects (font (size 0.7 0.7) (thickness 0.15)) (justify left bottom mirror))
    )
    (fp_rect (start -0.925 0.47) (end 0.925 -0.47)
      (stroke (width 0.05) (type default)) (fill none) (layer "B.CrtYd"))
    (fp_rect (start -0.5 0.25) (end 0.5 -0.25)
      (stroke (width 0.15) (type solid)) (fill none) (layer "B.Fab"))
    (pad "1" smd roundrect (at -0.48 0 90) (size 0.59 0.64) (layers "B.Cu" "B.Paste" "B.Mask") (roundrect_rratio 0.25)
      (net 88 "/Power/DCDC_EN") (pintype "passive"))
    (pad "2" smd roundrect (at 0.48 0 90) (size 0.59 0.64) (layers "B.Cu" "B.Paste" "B.Mask") (roundrect_rratio 0.25)
      (net 74 "Net-(C10-Pad2)") (pintype "passive"))
  )
	(footprint "antmicro-footprints:R_0402_1005Metric" (layer "B.Cu")
    (at 158.91 59.47 -90)
    (descr "Resistor SMD 0402")
    (tags "resistor SMD 0402")
    (property "Author" "Antmicro")
    (property "License" "Apache-2.0")
    (property "MPN" "CR0402-FX-1002GLF")
    (property "Manufacturer" "Bourns")
    (property "Sheetfile" "power.kicad_sch")
    (property "Sheetname" "Power")
    (property "Tolerance" "1%")
    (property "Val" "10k")
    (property "ki_description" "SMD Chip Resistor, 10 kohm, ± 1%, 62.5 mW, 0402 [1005 Metric], Thick Film, General Purpose")
    (property "ki_keywords" "0402, SMT, RESISTOR, PASSIVE")
    (attr smd)
    (fp_text reference "R20" (at -3.082 -0.348 90) (layer "B.SilkS")
        (effects (font (size 0.7 0.7) (thickness 0.15)) (justify left bottom mirror))
    )
    (fp_text value "R_10k_0402" (at -1.011843 -1.772047 90) (layer "B.Fab")
        (effects (font (size 0.7 0.7) (thickness 0.15)) (justify left bottom mirror))
    )
    (fp_text user "${REFERENCE}" (at -0.95 -3.168 90) (layer "B.Fab") hide
        (effects (font (size 0.7 0.7) (thickness 0.15)) (justify left bottom mirror))
    )
    (fp_text user "Author: Antmicro" (at -0.95 -4.169 90) (layer "B.Fab") hide
        (effects (font (size 0.7 0.7) (thickness 0.15)) (justify left bottom mirror))
    )
    (fp_text user "License: Apache-2.0" (at -0.95 -5.169 90) (layer "B.Fab") hide
        (effects (font (size 0.7 0.7) (thickness 0.15)) (justify left bottom mirror))
    )
    (fp_rect (start -0.925 0.47) (end 0.925 -0.47)
      (stroke (width 0.05) (type default)) (fill none) (layer "B.CrtYd"))
    (fp_rect (start -0.5 0.25) (end 0.5 -0.25)
      (stroke (width 0.15) (type solid)) (fill none) (layer "B.Fab"))
    (pad "1" smd roundrect (at -0.48 0 270) (size 0.59 0.64) (layers "B.Cu" "B.Paste" "B.Mask") (roundrect_rratio 0.25)
      (net 9 "/Power/TPS_3V3") (pintype "passive"))
    (pad "2" smd roundrect (at 0.48 0 270) (size 0.59 0.64) (layers "B.Cu" "B.Paste" "B.Mask") (roundrect_rratio 0.25)
      (net 155 "Net-(U3-GPIO7)") (pintype "passive"))
  )
	(footprint "antmicro-footprints:R_0402_1005Metric" (layer "B.Cu")
    (at 135.115 61.665)
    (descr "Resistor SMD 0402")
    (tags "resistor SMD 0402")
    (property "Author" "Antmicro")
    (property "License" "Apache-2.0")
    (property "MPN" "CR0402-FX-3301GLF")
    (property "Manufacturer" "Bourns")
    (property "Sheetfile" "tb.kicad_sch")
    (property "Sheetname" "TB Controller")
    (property "Tolerance" "1%")
    (property "Val" "3k3")
    (property "ki_description" "SMD Chip Resistor, 3.3 kohm, ± 1%, 63 mW, 0402 [1005 Metric], Thick Film, General Purpose")
    (property "ki_keywords" "0402, SMT, RESISTOR, PASSIVE")
    (attr smd)
    (fp_text reference "R50" (at -1.003 0.311 180) (layer "B.SilkS")
        (effects (font (size 0.7 0.7) (thickness 0.15)) (justify left bottom mirror))
    )
    (fp_text value "R_3k3_0402" (at -1.011843 -1.772047 180) (layer "B.Fab")
        (effects (font (size 0.7 0.7) (thickness 0.15)) (justify left bottom mirror))
    )
    (fp_text user "Author: Antmicro" (at -0.95 -4.169 180) (layer "B.Fab") hide
        (effects (font (size 0.7 0.7) (thickness 0.15)) (justify left bottom mirror))
    )
    (fp_text user "License: Apache-2.0" (at -0.95 -5.169 180) (layer "B.Fab") hide
        (effects (font (size 0.7 0.7) (thickness 0.15)) (justify left bottom mirror))
    )
    (fp_text user "${REFERENCE}" (at -0.95 -3.168 180) (layer "B.Fab") hide
        (effects (font (size 0.7 0.7) (thickness 0.15)) (justify left bottom mirror))
    )
    (fp_rect (start -0.925 0.47) (end 0.925 -0.47)
      (stroke (width 0.05) (type default)) (fill none) (layer "B.CrtYd"))
    (fp_rect (start -0.5 0.25) (end 0.5 -0.25)
      (stroke (width 0.15) (type solid)) (fill none) (layer "B.Fab"))
    (pad "1" smd roundrect (at -0.48 0) (size 0.59 0.64) (layers "B.Cu" "B.Paste" "B.Mask") (roundrect_rratio 0.25)
      (net 63 "SPI_MISO") (pintype "passive"))
    (pad "2" smd roundrect (at 0.48 0) (size 0.59 0.64) (layers "B.Cu" "B.Paste" "B.Mask") (roundrect_rratio 0.25)
      (net 2 "3V3_SYS") (pintype "passive"))
  )
)
